(kicad_pcb
	(version 20260206)
	(generator "pcbnew")
	(generator_version "10.0")
	(general
		(thickness 1.6)
		(legacy_teardrops no)
	)
	(paper "A4")
	(title_block
		(title "v1-chassis-manager — T6M_CM_d_v01_1031_1645.brd")
		(comment 1 "Open CloudServer (Microsoft) / footprints 263-270 of 2512")
	)
	(layers
		(0 "F.Cu" signal "TOP")
		(4 "In1.Cu" signal "GND1")
		(6 "In2.Cu" signal "IN1")
		(8 "In3.Cu" signal "VCC1")
		(10 "In4.Cu" signal "VCC2")
		(12 "In5.Cu" signal "GND2")
		(14 "In6.Cu" signal "IN2")
		(16 "In7.Cu" signal "IN3")
		(18 "In8.Cu" signal "GND3")
		(2 "B.Cu" signal "BOTTOM")
		(9 "F.Adhes" user "F.Adhesive")
		(11 "B.Adhes" user "B.Adhesive")
		(13 "F.Paste" user "Package Geometry/Pastemask Top")
		(15 "B.Paste" user "Package Geometry/Pastemask Bottom")
		(5 "F.SilkS" user "Ref Des/Silkscreen Top")
		(7 "B.SilkS" user "Ref Des/Silkscreen Bottom")
		(1 "F.Mask" user "Board Geometry/Soldermask Top")
		(3 "B.Mask" user "Board Geometry/Soldermask Bottom")
		(17 "Dwgs.User" user "User.Drawings")
		(19 "Cmts.User" user "User.Comments")
		(21 "Eco1.User" user "User.Eco1")
		(23 "Eco2.User" user "User.Eco2")
		(25 "Edge.Cuts" user "Board Geometry/Outline")
		(27 "Margin" user)
		(31 "F.CrtYd" user "Package Geometry/Place Bound Top")
		(29 "B.CrtYd" user "Package Geometry/Place Bound Bottom")
		(35 "F.Fab" user "Ref Des/Assembly Top")
		(33 "B.Fab" user "Ref Des/Assembly Bottom")
	)
	(footprint ""
		(layer "F.Cu")
		(at 162.296602 -175.827436 90)
		(property "Reference" "U57"
			(at -5.918708 -0.275082 0)
			(unlocked yes)
			(layer "F.SilkS")
			(effects
				(font
					(size 0.7874 0.5842)
					(thickness 0.1524)
				)
				(justify left)
			)
		)
		(property "Value" ""
			(at 0 0 90)
			(layer "F.Fab")
			(effects
				(font
					(size 1.27 1.27)
				)
			)
		)
		(duplicate_pad_numbers_are_jumpers no)
		(fp_line
			(start 4.9022 -2.0066)
			(end 4.9022 2.0066)
			(stroke
				(width 0.1524)
				(type default)
			)
			(layer "F.SilkS")
		)
		(fp_line
			(start -4.9022 -2.0066)
			(end 4.9022 -2.0066)
			(stroke
				(width 0.1524)
				(type default)
			)
			(layer "F.SilkS")
		)
		(fp_line
			(start -4.9022 -0.5842)
			(end -4.9022 -2.0066)
			(stroke
				(width 0.1524)
				(type default)
			)
			(layer "F.SilkS")
		)
		(fp_line
			(start -4.318 0)
			(end -4.9022 -0.5842)
			(stroke
				(width 0.1524)
				(type default)
			)
			(layer "F.SilkS")
		)
		(fp_line
			(start -4.9022 0.5842)
			(end -4.318 0)
			(stroke
				(width 0.1524)
				(type default)
			)
			(layer "F.SilkS")
		)
		(fp_line
			(start 4.9022 2.0066)
			(end -4.9022 2.0066)
			(stroke
				(width 0.1524)
				(type default)
			)
			(layer "F.SilkS")
		)
		(fp_line
			(start -4.9022 2.0066)
			(end -4.9022 0.5842)
			(stroke
				(width 0.1524)
				(type default)
			)
			(layer "F.SilkS")
		)
		(fp_circle
			(center -4.318 1.524)
			(end -4.318 1.778)
			(stroke
				(width 0.1524)
				(type default)
			)
			(fill no)
			(layer "F.SilkS")
		)
		(fp_rect
			(start -4.9022 3.6703)
			(end 4.9022 -3.6703)
			(stroke
				(width 0)
				(type default)
			)
			(fill no)
			(layer "F.CrtYd")
		)
		(pad "1" smd rect
			(at -4.225036 2.921 90)
			(size 0.3556 1.4986)
			(layers "F.Cu" "F.Mask" "F.Paste")
			(net "N54365611")
		)
		(pad "2" smd rect
			(at -3.57505 2.921 90)
			(size 0.3556 1.4986)
			(layers "F.Cu" "F.Mask" "F.Paste")
			(net "N54365613")
		)
		(pad "3" smd rect
			(at -2.925064 2.921 90)
			(size 0.3556 1.4986)
			(layers "F.Cu" "F.Mask" "F.Paste")
			(net "N54365625")
		)
		(pad "4" smd rect
			(at -2.275078 2.921 90)
			(size 0.3556 1.4986)
			(layers "F.Cu" "F.Mask" "F.Paste")
			(net "UART_RX_RP5_L")
		)
		(pad "5" smd rect
			(at -1.625092 2.921 90)
			(size 0.3556 1.4986)
			(layers "F.Cu" "F.Mask" "F.Paste")
			(net "UART_RI_RP5_L_N")
		)
		(pad "6" smd rect
			(at -0.975106 2.921 90)
			(size 0.3556 1.4986)
			(layers "F.Cu" "F.Mask" "F.Paste")
			(net "N54365542")
		)
		(pad "7" smd rect
			(at -0.32512 2.921 90)
			(size 0.3556 1.4986)
			(layers "F.Cu" "F.Mask" "F.Paste")
			(net "N54365542")
		)
		(pad "8" smd rect
			(at 0.32512 2.921 90)
			(size 0.3556 1.4986)
			(layers "F.Cu" "F.Mask" "F.Paste")
			(net "N54365542")
		)
		(pad "9" smd rect
			(at 0.975106 2.921 90)
			(size 0.3556 1.4986)
			(layers "F.Cu" "F.Mask" "F.Paste")
			(net "UART_RTS_RP5_L_N")
		)
		(pad "10" smd rect
			(at 1.625092 2.921 90)
			(size 0.3556 1.4986)
			(layers "F.Cu" "F.Mask" "F.Paste")
			(net "UART_TX_RP5_L")
		)
		(pad "11" smd rect
			(at 2.275078 2.921 90)
			(size 0.3556 1.4986)
			(layers "F.Cu" "F.Mask" "F.Paste")
			(net "UART_DTR_RP5_L_N")
		)
		(pad "12" smd rect
			(at 2.925064 2.921 90)
			(size 0.3556 1.4986)
			(layers "F.Cu" "F.Mask" "F.Paste")
			(net "CPLD_UART_DTR_P3_R_N")
		)
		(pad "13" smd rect
			(at 3.57505 2.921 90)
			(size 0.3556 1.4986)
			(layers "F.Cu" "F.Mask" "F.Paste")
			(net "CPLD_UART_TX_P3")
		)
		(pad "14" smd rect
			(at 4.225036 2.921 90)
			(size 0.3556 1.4986)
			(layers "F.Cu" "F.Mask" "F.Paste")
			(net "CPLD_UART_RTS_P3_R_N")
		)
		(pad "15" smd rect
			(at 4.225036 -2.921 90)
			(size 0.3556 1.4986)
			(layers "F.Cu" "F.Mask" "F.Paste")
			(net "Net_2298")
		)
		(pad "16" smd rect
			(at 3.57505 -2.921 90)
			(size 0.3556 1.4986)
			(layers "F.Cu" "F.Mask" "F.Paste")
			(net "Net_2299")
		)
		(pad "17" smd rect
			(at 2.925064 -2.921 90)
			(size 0.3556 1.4986)
			(layers "F.Cu" "F.Mask" "F.Paste")
			(net "Net_2300")
		)
		(pad "18" smd rect
			(at 2.275078 -2.921 90)
			(size 0.3556 1.4986)
			(layers "F.Cu" "F.Mask" "F.Paste")
			(net "CPLD_UART_RI_P3_LS_N")
		)
		(pad "19" smd rect
			(at 1.625092 -2.921 90)
			(size 0.3556 1.4986)
			(layers "F.Cu" "F.Mask" "F.Paste")
			(net "CPLD_UART_RX_P3_R")
		)
		(pad "20" smd rect
			(at 0.975106 -2.921 90)
			(size 0.3556 1.4986)
			(layers "F.Cu" "F.Mask" "F.Paste")
			(net "Net_2301")
		)
		(pad "21" smd rect
			(at 0.32512 -2.921 90)
			(size 0.3556 1.4986)
			(layers "F.Cu" "F.Mask" "F.Paste")
			(net "Net_2302")
		)
		(pad "22" smd rect
			(at -0.32512 -2.921 90)
			(size 0.3556 1.4986)
			(layers "F.Cu" "F.Mask" "F.Paste")
			(net "N54365556")
		)
		(pad "23" smd rect
			(at -0.975106 -2.921 90)
			(size 0.3556 1.4986)
			(layers "F.Cu" "F.Mask" "F.Paste")
			(net "N54365554")
		)
		(pad "24" smd rect
			(at -1.625092 -2.921 90)
			(size 0.3556 1.4986)
			(layers "F.Cu" "F.Mask" "F.Paste")
			(net "N54365603")
		)
		(pad "25" smd rect
			(at -2.275078 -2.921 90)
			(size 0.3556 1.4986)
			(layers "F.Cu" "F.Mask" "F.Paste")
			(net "GND")
		)
		(pad "26" smd rect
			(at -2.925064 -2.921 90)
			(size 0.3556 1.4986)
			(layers "F.Cu" "F.Mask" "F.Paste")
			(net "P3V3_NODE1")
		)
		(pad "27" smd rect
			(at -3.57505 -2.921 90)
			(size 0.3556 1.4986)
			(layers "F.Cu" "F.Mask" "F.Paste")
			(net "N54365623")
		)
		(pad "28" smd rect
			(at -4.225036 -2.921 90)
			(size 0.3556 1.4986)
			(layers "F.Cu" "F.Mask" "F.Paste")
			(net "N54365601")
		)
	)
	(footprint ""
		(layer "F.Cu")
		(at 110.170976 -153.54808)
		(property "Reference" "R1128"
			(at -0.694182 5.341874 0)
			(unlocked yes)
			(layer "F.SilkS")
			(effects
				(font
					(size 0.635 0.4064)
					(thickness 0.1524)
				)
				(justify left)
			)
		)
		(property "Value" ""
			(at 0 0 0)
			(layer "F.Fab")
			(effects
				(font
					(size 1.27 1.27)
				)
			)
		)
		(duplicate_pad_numbers_are_jumpers no)
		(fp_line
			(start -0.7874 -0.4064)
			(end 0.7874 -0.4064)
			(stroke
				(width 0.1524)
				(type default)
			)
			(layer "F.SilkS")
		)
		(fp_line
			(start -0.7874 0.4064)
			(end -0.7874 -0.4064)
			(stroke
				(width 0.1524)
				(type default)
			)
			(layer "F.SilkS")
		)
		(fp_line
			(start 0.7874 -0.4064)
			(end 0.7874 0.4064)
			(stroke
				(width 0.1524)
				(type default)
			)
			(layer "F.SilkS")
		)
		(fp_line
			(start 0.7874 0.4064)
			(end -0.7874 0.4064)
			(stroke
				(width 0.1524)
				(type default)
			)
			(layer "F.SilkS")
		)
		(fp_poly
			(pts
				(xy -0.508 0.2794) (xy -0.508 0.2286) (xy -0.635 0.2286) (xy -0.635 -0.254) (xy -0.5334 -0.254)
				(xy -0.5334 -0.2794) (xy 0.5334 -0.2794) (xy 0.5334 -0.254) (xy 0.635 -0.254) (xy 0.635 0.254) (xy 0.5334 0.254)
				(xy 0.5334 0.2794)
			)
			(stroke
				(width 0)
				(type default)
			)
			(fill no)
			(layer "F.CrtYd")
		)
		(pad "1" smd rect
			(at 0.40005 0)
			(size 0.4572 0.508)
			(layers "F.Cu" "F.Mask" "F.Paste")
			(net "N52411214")
		)
		(pad "2" smd rect
			(at -0.40005 0)
			(size 0.4572 0.508)
			(layers "F.Cu" "F.Mask" "F.Paste")
			(net "N52411212")
		)
	)
	(footprint ""
		(layer "F.Cu")
		(at 99.516184 -17.689322)
		(property "Reference" "R205"
			(at 0.049276 -1.34747 0)
			(unlocked yes)
			(layer "F.SilkS")
			(effects
				(font
					(size 0.7874 0.5842)
					(thickness 0.1524)
				)
				(justify left)
			)
		)
		(property "Value" ""
			(at 0 0 0)
			(layer "F.Fab")
			(effects
				(font
					(size 1.27 1.27)
				)
			)
		)
		(duplicate_pad_numbers_are_jumpers no)
		(fp_line
			(start -0.7874 -0.4064)
			(end 0.7874 -0.4064)
			(stroke
				(width 0.1524)
				(type default)
			)
			(layer "F.SilkS")
		)
		(fp_line
			(start -0.7874 0.4064)
			(end -0.7874 -0.4064)
			(stroke
				(width 0.1524)
				(type default)
			)
			(layer "F.SilkS")
		)
		(fp_line
			(start 0.7874 -0.4064)
			(end 0.7874 0.4064)
			(stroke
				(width 0.1524)
				(type default)
			)
			(layer "F.SilkS")
		)
		(fp_line
			(start 0.7874 0.4064)
			(end -0.7874 0.4064)
			(stroke
				(width 0.1524)
				(type default)
			)
			(layer "F.SilkS")
		)
		(fp_poly
			(pts
				(xy -0.508 0.2794) (xy -0.508 0.2286) (xy -0.635 0.2286) (xy -0.635 -0.254) (xy -0.5334 -0.254)
				(xy -0.5334 -0.2794) (xy 0.5334 -0.2794) (xy 0.5334 -0.254) (xy 0.635 -0.254) (xy 0.635 0.254) (xy 0.5334 0.254)
				(xy 0.5334 0.2794)
			)
			(stroke
				(width 0)
				(type default)
			)
			(fill no)
			(layer "F.CrtYd")
		)
		(pad "1" smd rect
			(at 0.40005 0)
			(size 0.4572 0.508)
			(layers "F.Cu" "F.Mask" "F.Paste")
			(net "GND")
		)
		(pad "2" smd rect
			(at -0.40005 0)
			(size 0.4572 0.508)
			(layers "F.Cu" "F.Mask" "F.Paste")
			(net "PD_NODE1_DM7")
		)
	)
	(footprint ""
		(layer "F.Cu")
		(at 70.377812 -1.685544 180)
		(property "Reference" "R1237"
			(at 1.09982 -1.040892 0)
			(unlocked yes)
			(layer "F.SilkS")
			(effects
				(font
					(size 0.7874 0.5842)
					(thickness 0.1524)
				)
				(justify left)
			)
		)
		(property "Value" ""
			(at 0 0 180)
			(layer "F.Fab")
			(effects
				(font
					(size 1.27 1.27)
				)
			)
		)
		(duplicate_pad_numbers_are_jumpers no)
		(fp_line
			(start 0.7874 0.4064)
			(end -0.7874 0.4064)
			(stroke
				(width 0.1524)
				(type default)
			)
			(layer "F.SilkS")
		)
		(fp_line
			(start 0.7874 -0.4064)
			(end 0.7874 0.4064)
			(stroke
				(width 0.1524)
				(type default)
			)
			(layer "F.SilkS")
		)
		(fp_line
			(start -0.7874 0.4064)
			(end -0.7874 -0.4064)
			(stroke
				(width 0.1524)
				(type default)
			)
			(layer "F.SilkS")
		)
		(fp_line
			(start -0.7874 -0.4064)
			(end 0.7874 -0.4064)
			(stroke
				(width 0.1524)
				(type default)
			)
			(layer "F.SilkS")
		)
		(fp_poly
			(pts
				(xy -0.508 0.2794) (xy -0.508 0.2286) (xy -0.635 0.2286) (xy -0.635 -0.254) (xy -0.5334 -0.254)
				(xy -0.5334 -0.2794) (xy 0.5334 -0.2794) (xy 0.5334 -0.254) (xy 0.635 -0.254) (xy 0.635 0.254) (xy 0.5334 0.254)
				(xy 0.5334 0.2794)
			)
			(stroke
				(width 0)
				(type default)
			)
			(fill no)
			(layer "F.CrtYd")
		)
		(pad "1" smd rect
			(at 0.40005 0 180)
			(size 0.4572 0.508)
			(layers "F.Cu" "F.Mask" "F.Paste")
			(net "GND")
		)
		(pad "2" smd rect
			(at -0.40005 0 180)
			(size 0.4572 0.508)
			(layers "F.Cu" "F.Mask" "F.Paste")
			(net "FM_CPLD_NODE1_P3V3_EN")
		)
	)
	(footprint ""
		(layer "F.Cu")
		(at 47.10176 -188.126624 90)
		(property "Reference" "R852"
			(at 4.548886 0.205232 90)
			(unlocked yes)
			(layer "F.SilkS")
			(effects
				(font
					(size 0.7874 0.5842)
					(thickness 0.1524)
				)
				(justify left)
			)
		)
		(property "Value" ""
			(at 0 0 90)
			(layer "F.Fab")
			(effects
				(font
					(size 1.27 1.27)
				)
			)
		)
		(duplicate_pad_numbers_are_jumpers no)
		(fp_line
			(start 0.7874 -0.4064)
			(end 0.7874 0.4064)
			(stroke
				(width 0.1524)
				(type default)
			)
			(layer "F.SilkS")
		)
		(fp_line
			(start -0.7874 -0.4064)
			(end 0.7874 -0.4064)
			(stroke
				(width 0.1524)
				(type default)
			)
			(layer "F.SilkS")
		)
		(fp_line
			(start 0.7874 0.4064)
			(end -0.7874 0.4064)
			(stroke
				(width 0.1524)
				(type default)
			)
			(layer "F.SilkS")
		)
		(fp_line
			(start -0.7874 0.4064)
			(end -0.7874 -0.4064)
			(stroke
				(width 0.1524)
				(type default)
			)
			(layer "F.SilkS")
		)
		(fp_poly
			(pts
				(xy -0.508 0.2794) (xy -0.508 0.2286) (xy -0.635 0.2286) (xy -0.635 -0.254) (xy -0.5334 -0.254)
				(xy -0.5334 -0.2794) (xy 0.5334 -0.2794) (xy 0.5334 -0.254) (xy 0.635 -0.254) (xy 0.635 0.254) (xy 0.5334 0.254)
				(xy 0.5334 0.2794)
			)
			(stroke
				(width 0)
				(type default)
			)
			(fill no)
			(layer "F.CrtYd")
		)
		(pad "1" smd rect
			(at 0.40005 0 90)
			(size 0.4572 0.508)
			(layers "F.Cu" "F.Mask" "F.Paste")
			(net "PSU6_AC_OK_R")
		)
		(pad "2" smd rect
			(at -0.40005 0 90)
			(size 0.4572 0.508)
			(layers "F.Cu" "F.Mask" "F.Paste")
			(net "GND")
		)
	)
	(footprint ""
		(layer "F.Cu")
		(at 127.03556 -188.126624 90)
		(property "Reference" "C764"
			(at 4.949444 -0.396748 90)
			(unlocked yes)
			(layer "F.SilkS")
			(effects
				(font
					(size 0.7874 0.5842)
					(thickness 0.1524)
				)
				(justify left)
			)
		)
		(property "Value" ""
			(at 0 0 90)
			(layer "F.Fab")
			(effects
				(font
					(size 1.27 1.27)
				)
			)
		)
		(duplicate_pad_numbers_are_jumpers no)
		(fp_line
			(start 0.7874 -0.4064)
			(end 0.7874 0.4064)
			(stroke
				(width 0.1524)
				(type default)
			)
			(layer "F.SilkS")
		)
		(fp_line
			(start -0.7874 -0.4064)
			(end 0.7874 -0.4064)
			(stroke
				(width 0.1524)
				(type default)
			)
			(layer "F.SilkS")
		)
		(fp_line
			(start 0 0.381)
			(end 0 -0.381)
			(stroke
				(width 0.1524)
				(type default)
			)
			(layer "F.SilkS")
		)
		(fp_line
			(start 0.7874 0.4064)
			(end -0.7874 0.4064)
			(stroke
				(width 0.1524)
				(type default)
			)
			(layer "F.SilkS")
		)
		(fp_line
			(start -0.7874 0.4064)
			(end -0.7874 -0.4064)
			(stroke
				(width 0.1524)
				(type default)
			)
			(layer "F.SilkS")
		)
		(fp_poly
			(pts
				(xy -0.5334 0.254) (xy -0.635 0.254) (xy -0.635 0.2286) (xy -0.635 -0.254) (xy -0.5334 -0.254) (xy -0.5334 -0.2794)
				(xy 0.5334 -0.2794) (xy 0.5334 -0.254) (xy 0.635 -0.254) (xy 0.635 0.254) (xy 0.5334 0.254) (xy 0.5334 0.2794)
				(xy -0.508 0.2794) (xy -0.5334 0.2794)
			)
			(stroke
				(width 0)
				(type default)
			)
			(fill no)
			(layer "F.CrtYd")
		)
		(pad "1" smd rect
			(at 0.40005 0 90)
			(size 0.4572 0.508)
			(layers "F.Cu" "F.Mask" "F.Paste")
			(net "UART_T10_NODE4_TXD_R")
		)
		(pad "2" smd rect
			(at -0.40005 0 90)
			(size 0.4572 0.508)
			(layers "F.Cu" "F.Mask" "F.Paste")
			(net "GND")
		)
	)
	(footprint ""
		(layer "F.Cu")
		(at 60.05957 -108.23829 180)
		(property "Reference" "PC17"
			(at 1.977644 -5.782056 0)
			(unlocked yes)
			(layer "F.SilkS")
			(effects
				(font
					(size 0.7874 0.5842)
					(thickness 0.1524)
				)
				(justify left)
			)
		)
		(property "Value" ""
			(at 0 0 180)
			(layer "F.Fab")
			(effects
				(font
					(size 1.27 1.27)
				)
			)
		)
		(duplicate_pad_numbers_are_jumpers no)
		(fp_line
			(start 1.905 0.8636)
			(end -1.905 0.8636)
			(stroke
				(width 0.1524)
				(type default)
			)
			(layer "F.SilkS")
		)
		(fp_line
			(start 1.905 -0.8636)
			(end 1.905 0.8636)
			(stroke
				(width 0.1524)
				(type default)
			)
			(layer "F.SilkS")
		)
		(fp_line
			(start 0 0.8382)
			(end 0 -0.8382)
			(stroke
				(width 0.1524)
				(type default)
			)
			(layer "F.SilkS")
		)
		(fp_line
			(start -1.905 0.8636)
			(end -1.905 -0.8636)
			(stroke
				(width 0.1524)
				(type default)
			)
			(layer "F.SilkS")
		)
		(fp_line
			(start -1.905 -0.8636)
			(end 1.905 -0.8636)
			(stroke
				(width 0.1524)
				(type default)
			)
			(layer "F.SilkS")
		)
		(fp_rect
			(start -1.524 0.7366)
			(end 1.524 -0.7366)
			(stroke
				(width 0)
				(type default)
			)
			(fill no)
			(layer "F.CrtYd")
		)
		(pad "1" smd rect
			(at 0.94996 0 180)
			(size 1.1176 1.3716)
			(layers "F.Cu" "F.Mask" "F.Paste")
			(net "P3V3_STB_NODE1")
		)
		(pad "2" smd rect
			(at -0.94996 0 180)
			(size 1.1176 1.3716)
			(layers "F.Cu" "F.Mask" "F.Paste")
			(net "GND")
		)
	)
	(footprint ""
		(layer "F.Cu")
		(at 115.93576 -175.426624 90)
		(property "Reference" "R1048"
			(at -57.01538 32.987488 90)
			(unlocked yes)
			(layer "F.SilkS")
			(effects
				(font
					(size 0.7874 0.5842)
					(thickness 0.1524)
				)
				(justify left)
			)
		)
		(property "Value" ""
			(at 0 0 90)
			(layer "F.Fab")
			(effects
				(font
					(size 1.27 1.27)
				)
			)
		)
		(duplicate_pad_numbers_are_jumpers no)
		(fp_line
			(start 0.7874 -0.4064)
			(end 0.7874 0.4064)
			(stroke
				(width 0.1524)
				(type default)
			)
			(layer "F.SilkS")
		)
		(fp_line
			(start -0.7874 -0.4064)
			(end 0.7874 -0.4064)
			(stroke
				(width 0.1524)
				(type default)
			)
			(layer "F.SilkS")
		)
		(fp_line
			(start 0.7874 0.4064)
			(end -0.7874 0.4064)
			(stroke
				(width 0.1524)
				(type default)
			)
			(layer "F.SilkS")
		)
		(fp_line
			(start -0.7874 0.4064)
			(end -0.7874 -0.4064)
			(stroke
				(width 0.1524)
				(type default)
			)
			(layer "F.SilkS")
		)
		(fp_poly
			(pts
				(xy -0.508 0.2794) (xy -0.508 0.2286) (xy -0.635 0.2286) (xy -0.635 -0.254) (xy -0.5334 -0.254)
				(xy -0.5334 -0.2794) (xy 0.5334 -0.2794) (xy 0.5334 -0.254) (xy 0.635 -0.254) (xy 0.635 0.254) (xy 0.5334 0.254)
				(xy 0.5334 0.2794)
			)
			(stroke
				(width 0)
				(type default)
			)
			(fill no)
			(layer "F.CrtYd")
		)
		(pad "1" smd rect
			(at 0.40005 0 90)
			(size 0.4572 0.508)
			(layers "F.Cu" "F.Mask" "F.Paste")
			(net "N31341801")
		)
		(pad "2" smd rect
			(at -0.40005 0 90)
			(size 0.4572 0.508)
			(layers "F.Cu" "F.Mask" "F.Paste")
			(net "GND")
		)
	)
)
